# T6G (Grand Teton) — schematic netlist excerpt (pin names and nets, part order shuffled) for the footprints in the layout excerpt that follows; sources: Cadence DE-HDL packaged netlist, KiCad conversion of 04192023_DAF0TMB3IC0_F0TG_MB_C_brd_V02_OCP.brd

R3722  Q_RES  0 5% CHIP  pkg 0402LF  page 252 : A = SMB_LM75_3_3V3AUX_SDA_R ; B = SMB_LM75_3_3V3AUX_SDA
R4489  Q_RES  4.75K 1% CHIP  pkg 0402LF  page 182 : A = P3V3_AUX ; B = CLK_9ZXL045_P0_SADR0

(kicad_pcb
	(version 20260206)
	(generator "pcbnew")
	(generator_version "10.0")
	(general
		(thickness 1.6)
		(legacy_teardrops no)
	)
	(paper "A4")
	(title_block
		(title "04192023_DAF0TMB3IC0_F0TG_MB_C_brd_V02_OCP.brd")
		(comment 1 "Grand Teton / footprints 2623-2624 of 8354")
	)
	(layers
		(0 "F.Cu" signal "TOP")
		(4 "In1.Cu" signal "GND")
		(6 "In2.Cu" signal "IN1")
		(8 "In3.Cu" signal "GND1")
		(10 "In4.Cu" signal "IN2")
		(12 "In5.Cu" signal "GND2")
		(14 "In6.Cu" signal "IN3")
		(16 "In7.Cu" signal "GND3")
		(18 "In8.Cu" signal "VCC")
		(20 "In9.Cu" signal "VCC1")
		(22 "In10.Cu" signal "GND4")
		(24 "In11.Cu" signal "IN4")
		(26 "In12.Cu" signal "GND5")
		(28 "In13.Cu" signal "IN5")
		(30 "In14.Cu" signal "GND6")
		(32 "In15.Cu" signal "IN6")
		(34 "In16.Cu" signal "GND7")
		(2 "B.Cu" signal "BOTTOM")
		(9 "F.Adhes" user "F.Adhesive")
		(11 "B.Adhes" user "B.Adhesive")
		(13 "F.Paste" user "Package Geometry/Pastemask Top")
		(15 "B.Paste" user "Package Geometry/Pastemask Bottom")
		(5 "F.SilkS" user "Ref Des/Silkscreen Top")
		(7 "B.SilkS" user "Ref Des/Silkscreen Bottom")
		(1 "F.Mask" user "Board Geometry/Soldermask Top")
		(3 "B.Mask" user "Board Geometry/Soldermask Bottom")
		(17 "Dwgs.User" user "User.Drawings")
		(19 "Cmts.User" user "User.Comments")
		(21 "Eco1.User" user "User.Eco1")
		(23 "Eco2.User" user "User.Eco2")
		(25 "Edge.Cuts" user "Board Geometry/Outline")
		(27 "Margin" user)
		(31 "F.CrtYd" user "Package Geometry/Place Bound Top")
		(29 "B.CrtYd" user "Package Geometry/Place Bound Bottom")
		(35 "F.Fab" user "Ref Des/Assembly Top")
		(33 "B.Fab" user "Ref Des/Assembly Bottom")
	)
	(footprint ""
		(layer "F.Cu")
		(at 279.527 -416.306)
		(property "Reference" "R4489"
			(at 0 0 0)
			(layer "F.SilkS")
			(hide yes)
			(effects
				(font
					(size 1.27 1.27)
				)
			)
		)
		(property "Value" ""
			(at 0 0 0)
			(layer "F.Fab")
			(effects
				(font
					(size 1.27 1.27)
				)
			)
		)
		(duplicate_pad_numbers_are_jumpers no)
		(fp_line
			(start -0.7874 -0.4064)
			(end 0.7874 -0.4064)
			(stroke
				(width 0.1524)
				(type default)
			)
			(layer "F.SilkS")
		)
		(fp_line
			(start -0.7874 0.4064)
			(end -0.7874 -0.4064)
			(stroke
				(width 0.1524)
				(type default)
			)
			(layer "F.SilkS")
		)
		(fp_line
			(start 0.7874 -0.4064)
			(end 0.7874 0.4064)
			(stroke
				(width 0.1524)
				(type default)
			)
			(layer "F.SilkS")
		)
		(fp_line
			(start 0.7874 0.4064)
			(end -0.7874 0.4064)
			(stroke
				(width 0.1524)
				(type default)
			)
			(layer "F.SilkS")
		)
		(fp_line
			(start -0.67945 -0.305054)
			(end -0.12065 -0.305054)
			(stroke
				(width 0.1)
				(type default)
			)
			(layer "F.Fab")
		)
		(fp_line
			(start -0.67945 0.3048)
			(end -0.67945 -0.305054)
			(stroke
				(width 0.1)
				(type default)
			)
			(layer "F.Fab")
		)
		(fp_line
			(start -0.12065 -0.305054)
			(end -0.12065 -0.2794)
			(stroke
				(width 0.1)
				(type default)
			)
			(layer "F.Fab")
		)
		(fp_line
			(start -0.12065 -0.2794)
			(end 0.12065 -0.2794)
			(stroke
				(width 0.1)
				(type default)
			)
			(layer "F.Fab")
		)
		(fp_line
			(start -0.12065 0.2794)
			(end -0.12065 0.3048)
			(stroke
				(width 0.1)
				(type default)
			)
			(layer "F.Fab")
		)
		(fp_line
			(start -0.12065 0.3048)
			(end -0.67945 0.3048)
			(stroke
				(width 0.1)
				(type default)
			)
			(layer "F.Fab")
		)
		(fp_line
			(start 0.120396 0.2794)
			(end -0.12065 0.2794)
			(stroke
				(width 0.1)
				(type default)
			)
			(layer "F.Fab")
		)
		(fp_line
			(start 0.120396 0.3048)
			(end 0.120396 0.2794)
			(stroke
				(width 0.1)
				(type default)
			)
			(layer "F.Fab")
		)
		(fp_line
			(start 0.12065 -0.3048)
			(end 0.67945 -0.3048)
			(stroke
				(width 0.1)
				(type default)
			)
			(layer "F.Fab")
		)
		(fp_line
			(start 0.12065 -0.2794)
			(end 0.12065 -0.3048)
			(stroke
				(width 0.1)
				(type default)
			)
			(layer "F.Fab")
		)
		(fp_line
			(start 0.67945 -0.3048)
			(end 0.67945 0.3048)
			(stroke
				(width 0.1)
				(type default)
			)
			(layer "F.Fab")
		)
		(fp_line
			(start 0.67945 0.3048)
			(end 0.120396 0.3048)
			(stroke
				(width 0.1)
				(type default)
			)
			(layer "F.Fab")
		)
		(pad "1" smd circle
			(at -0.40005 0)
			(size 0 0)
			(layers "F.Cu" "F.Mask" "F.Paste")
			(net "P3V3_AUX")
		)
		(pad "2" smd circle
			(at 0.40005 0)
			(size 0 0)
			(layers "F.Cu" "F.Mask" "F.Paste")
			(net "CLK_9ZXL045_P0_SADR0")
		)
	)
	(footprint ""
		(layer "F.Cu")
		(at 271.085056 -114.21237)
		(property "Reference" "R3722"
			(at 0 0 0)
			(layer "F.SilkS")
			(hide yes)
			(effects
				(font
					(size 1.27 1.27)
				)
			)
		)
		(property "Value" ""
			(at 0 0 0)
			(layer "F.Fab")
			(effects
				(font
					(size 1.27 1.27)
				)
			)
		)
		(duplicate_pad_numbers_are_jumpers no)
		(fp_line
			(start -0.7874 -0.4064)
			(end 0.7874 -0.4064)
			(stroke
				(width 0.1524)
				(type default)
			)
			(layer "F.SilkS")
		)
		(fp_line
			(start -0.7874 0.4064)
			(end -0.7874 -0.4064)
			(stroke
				(width 0.1524)
				(type default)
			)
			(layer "F.SilkS")
		)
		(fp_line
			(start 0.7874 -0.4064)
			(end 0.7874 0.4064)
			(stroke
				(width 0.1524)
				(type default)
			)
			(layer "F.SilkS")
		)
		(fp_line
			(start 0.7874 0.4064)
			(end -0.7874 0.4064)
			(stroke
				(width 0.1524)
				(type default)
			)
			(layer "F.SilkS")
		)
		(fp_line
			(start -0.67945 -0.305054)
			(end -0.12065 -0.305054)
			(stroke
				(width 0.1)
				(type default)
			)
			(layer "F.Fab")
		)
		(fp_line
			(start -0.67945 0.3048)
			(end -0.67945 -0.305054)
			(stroke
				(width 0.1)
				(type default)
			)
			(layer "F.Fab")
		)
		(fp_line
			(start -0.12065 -0.305054)
			(end -0.12065 -0.2794)
			(stroke
				(width 0.1)
				(type default)
			)
			(layer "F.Fab")
		)
		(fp_line
			(start -0.12065 -0.2794)
			(end 0.12065 -0.2794)
			(stroke
				(width 0.1)
				(type default)
			)
			(layer "F.Fab")
		)
		(fp_line
			(start -0.12065 0.2794)
			(end -0.12065 0.3048)
			(stroke
				(width 0.1)
				(type default)
			)
			(layer "F.Fab")
		)
		(fp_line
			(start -0.12065 0.3048)
			(end -0.67945 0.3048)
			(stroke
				(width 0.1)
				(type default)
			)
			(layer "F.Fab")
		)
		(fp_line
			(start 0.120396 0.2794)
			(end -0.12065 0.2794)
			(stroke
				(width 0.1)
				(type default)
			)
			(layer "F.Fab")
		)
		(fp_line
			(start 0.120396 0.3048)
			(end 0.120396 0.2794)
			(stroke
				(width 0.1)
				(type default)
			)
			(layer "F.Fab")
		)
		(fp_line
			(start 0.12065 -0.3048)
			(end 0.67945 -0.3048)
			(stroke
				(width 0.1)
				(type default)
			)
			(layer "F.Fab")
		)
		(fp_line
			(start 0.12065 -0.2794)
			(end 0.12065 -0.3048)
			(stroke
				(width 0.1)
				(type default)
			)
			(layer "F.Fab")
		)
		(fp_line
			(start 0.67945 -0.3048)
			(end 0.67945 0.3048)
			(stroke
				(width 0.1)
				(type default)
			)
			(layer "F.Fab")
		)
		(fp_line
			(start 0.67945 0.3048)
			(end 0.120396 0.3048)
			(stroke
				(width 0.1)
				(type default)
			)
			(layer "F.Fab")
		)
		(pad "1" smd circle
			(at -0.40005 0)
			(size 0 0)
			(layers "F.Cu" "F.Mask" "F.Paste")
			(net "SMB_LM75_3_3V3AUX_SDA_R")
		)
		(pad "2" smd circle
			(at 0.40005 0)
			(size 0 0)
			(layers "F.Cu" "F.Mask" "F.Paste")
			(net "SMB_LM75_3_3V3AUX_SDA")
		)
	)
)
